(kicad_pcb
	(version 20241229)
	(generator "pcbnew")
	(generator_version "9.0")
	(general
		(thickness 1.62)
		(legacy_teardrops no)
	)
	(paper "A4")
	(title_block
		(title "OCuLink to 10GbE adapter")
		(date "2026-02-23")
		(rev "1.1.0")
		(company "Antmicro Ltd")
		(comment 1 "www.antmicro.com")
		(comment 9 "footprints 495-499 of 510")
	)
	(layers
		(0 "F.Cu" signal)
		(4 "In1.Cu" signal)
		(6 "In2.Cu" signal)
		(8 "In3.Cu" signal)
		(10 "In4.Cu" signal)
		(12 "In5.Cu" signal)
		(14 "In6.Cu" signal)
		(2 "B.Cu" signal)
		(9 "F.Adhes" user "F.Adhesive")
		(11 "B.Adhes" user "B.Adhesive")
		(13 "F.Paste" user)
		(15 "B.Paste" user)
		(5 "F.SilkS" user "F.Silkscreen")
		(7 "B.SilkS" user "B.Silkscreen")
		(1 "F.Mask" user)
		(3 "B.Mask" user)
		(17 "Dwgs.User" user "User.Drawings")
		(19 "Cmts.User" user "User.Comments")
		(21 "Eco1.User" user "User.Eco1")
		(23 "Eco2.User" user "User.Eco2")
		(25 "Edge.Cuts" user)
		(27 "Margin" user)
		(31 "F.CrtYd" user "F.Courtyard")
		(29 "B.CrtYd" user "B.Courtyard")
		(35 "F.Fab" user)
		(33 "B.Fab" user)
	)
	(footprint "antmicro-footprints:SOD-523"
		(layer "B.Cu")
		(at 74.9 86.75 -90)
		(property "Reference" "D12"
			(at 1.12 -2.57 90)
			(layer "B.SilkS")
			(effects
				(font
					(size 0.7 0.7)
					(thickness 0.15)
				)
				(justify right bottom mirror)
			)
		)
		(property "Value" "RB521S30T1G"
			(at 0 -1.499 90)
			(layer "B.Fab")
			(hide yes)
			(effects
				(font
					(size 0.7 0.7)
					(thickness 0.15)
				)
				(justify left bottom mirror)
			)
		)
		(property "Datasheet" "https://www.onsemi.com/pdf/datasheet/rb521s30t1-d.pdf"
			(at 0 0 90)
			(layer "B.Fab")
			(hide yes)
			(effects
				(font
					(size 1.27 1.27)
					(thickness 0.15)
				)
				(justify mirror)
			)
		)
		(property "Description" "Small Signal Schottky Diode, Single, 30 V, 200 mA, 500 mV, 1 A, 125 °C"
			(at 0 0 90)
			(layer "B.Fab")
			(hide yes)
			(effects
				(font
					(size 1.27 1.27)
					(thickness 0.15)
				)
				(justify mirror)
			)
		)
		(property "MPN" "RB521S30T1G"
			(at 0 0 270)
			(unlocked yes)
			(layer "B.Fab")
			(hide yes)
			(effects
				(font
					(size 1 1)
					(thickness 0.15)
				)
				(justify mirror)
			)
		)
		(property "Manufacturer" "ON Semiconductor"
			(at 0 0 270)
			(unlocked yes)
			(layer "B.Fab")
			(hide yes)
			(effects
				(font
					(size 1 1)
					(thickness 0.15)
				)
				(justify mirror)
			)
		)
		(property "Author" "Antmicro"
			(at 0 0 270)
			(unlocked yes)
			(layer "B.Fab")
			(hide yes)
			(effects
				(font
					(size 1 1)
					(thickness 0.15)
				)
				(justify mirror)
			)
		)
		(property "License" "Apache-2.0"
			(at 0 0 270)
			(unlocked yes)
			(layer "B.Fab")
			(hide yes)
			(effects
				(font
					(size 1 1)
					(thickness 0.15)
				)
				(justify mirror)
			)
		)
		(sheetname "/Flash memory/")
		(sheetfile "flash-memory.kicad_sch")
		(attr smd)
		(fp_line
			(start -0.35 0.5)
			(end -0.35 -0.5)
			(stroke
				(width 0.15)
				(type solid)
			)
			(layer "B.SilkS")
		)
		(fp_rect
			(start -1 0.6)
			(end 1 -0.6)
			(stroke
				(width 0.05)
				(type solid)
			)
			(fill no)
			(layer "B.CrtYd")
		)
		(fp_line
			(start -0.652 0.425)
			(end 0.65 0.425)
			(stroke
				(width 0.15)
				(type solid)
			)
			(layer "B.Fab")
		)
		(fp_line
			(start 0.65 0.425)
			(end 0.65 -0.423)
			(stroke
				(width 0.15)
				(type solid)
			)
			(layer "B.Fab")
		)
		(fp_line
			(start -0.35 0.4)
			(end -0.35 -0.4)
			(stroke
				(width 0.15)
				(type solid)
			)
			(layer "B.Fab")
		)
		(fp_line
			(start -0.652 -0.423)
			(end -0.652 0.425)
			(stroke
				(width 0.15)
				(type solid)
			)
			(layer "B.Fab")
		)
		(fp_line
			(start -0.652 -0.423)
			(end 0.65 -0.423)
			(stroke
				(width 0.15)
				(type solid)
			)
			(layer "B.Fab")
		)
		(pad "1" smd roundrect
			(at -0.701 0 270)
			(size 0.5 0.6)
			(layers "B.Cu" "B.Mask" "B.Paste")
			(roundrect_rratio 0.25)
			(net 110 "/Flash memory/+3V3_FLASH")
			(pinfunction "C")
			(pintype "passive")
		)
		(pad "2" smd roundrect
			(at 0.699 0 270)
			(size 0.5 0.6)
			(layers "B.Cu" "B.Mask" "B.Paste")
			(roundrect_rratio 0.25)
			(net 7 "+3V3")
			(pinfunction "A")
			(pintype "passive")
		)
	)
	(footprint "antmicro-footprints:R_0402_1005Metric"
		(layer "B.Cu")
		(at 109.49 86.76 90)
		(descr "Resistor SMD 0402")
		(tags "resistor SMD 0402")
		(property "Reference" "R128"
			(at 0.81 -0.31 90)
			(layer "B.SilkS")
			(effects
				(font
					(size 0.7 0.7)
					(thickness 0.15)
				)
				(justify right top mirror)
			)
		)
		(property "Value" "R_1k_0402"
			(at -1.011843 -1.772046 90)
			(layer "B.Fab")
			(hide yes)
			(effects
				(font
					(size 0.7 0.7)
					(thickness 0.15)
				)
				(justify right top mirror)
			)
		)
		(property "Datasheet" "https://www.bourns.com/docs/product-datasheets/cr.pdf"
			(at 0 0 90)
			(layer "B.Fab")
			(hide yes)
			(effects
				(font
					(size 1.27 1.27)
					(thickness 0.15)
				)
				(justify mirror)
			)
		)
		(property "Description" "SMD Chip Resistor, 1 kohm, ± 1%, 63 mW, 0402 [1005 Metric], Thick Film, General Purpose"
			(at 0 0 90)
			(layer "B.Fab")
			(hide yes)
			(effects
				(font
					(size 1.27 1.27)
					(thickness 0.15)
				)
				(justify mirror)
			)
		)
		(property "MPN" "CR0402-FX-1001GLF"
			(at 0 0 90)
			(unlocked yes)
			(layer "B.Fab")
			(hide yes)
			(effects
				(font
					(size 1 1)
					(thickness 0.15)
				)
				(justify mirror)
			)
		)
		(property "Manufacturer" "Bourns"
			(at 0 0 90)
			(unlocked yes)
			(layer "B.Fab")
			(hide yes)
			(effects
				(font
					(size 1 1)
					(thickness 0.15)
				)
				(justify mirror)
			)
		)
		(property "License" "Apache-2.0"
			(at 0 0 90)
			(unlocked yes)
			(layer "B.Fab")
			(hide yes)
			(effects
				(font
					(size 1 1)
					(thickness 0.15)
				)
				(justify mirror)
			)
		)
		(property "Author" "Antmicro"
			(at 0 0 90)
			(unlocked yes)
			(layer "B.Fab")
			(hide yes)
			(effects
				(font
					(size 1 1)
					(thickness 0.15)
				)
				(justify mirror)
			)
		)
		(property "Val" "1k"
			(at 0 0 90)
			(unlocked yes)
			(layer "B.Fab")
			(hide yes)
			(effects
				(font
					(size 1 1)
					(thickness 0.15)
				)
				(justify mirror)
			)
		)
		(property "Tolerance" "1%"
			(at 0 0 90)
			(unlocked yes)
			(layer "B.Fab")
			(hide yes)
			(effects
				(font
					(size 1 1)
					(thickness 0.15)
				)
				(justify mirror)
			)
		)
		(sheetname "/X710-AT2 RSVD/")
		(sheetfile "x710-at2-rsvd.kicad_sch")
		(attr smd)
		(fp_rect
			(start -0.925 0.47)
			(end 0.925 -0.47)
			(stroke
				(width 0.05)
				(type default)
			)
			(fill no)
			(layer "B.CrtYd")
		)
		(fp_rect
			(start -0.5 0.25)
			(end 0.5 -0.25)
			(stroke
				(width 0.15)
				(type solid)
			)
			(fill no)
			(layer "B.Fab")
		)
		(pad "1" smd roundrect
			(at -0.48 0 90)
			(size 0.59 0.64)
			(layers "B.Cu" "B.Mask" "B.Paste")
			(roundrect_rratio 0.25)
			(net 119 "/X710-AT2 RSVD/DEBUG_Y20")
			(pintype "passive")
		)
		(pad "2" smd roundrect
			(at 0.48 0 90)
			(size 0.59 0.64)
			(layers "B.Cu" "B.Mask" "B.Paste")
			(roundrect_rratio 0.25)
			(net 114 "/X710-AT2 RSVD/DEBUG_EN")
			(pintype "passive")
		)
	)
	(footprint "antmicro-footprints:C_0402_1005Metric"
		(layer "B.Cu")
		(at 103.95 132.39 180)
		(descr "Capacitor SMD 0402")
		(tags "capacitor SMD 0402")
		(property "Reference" "C65"
			(at -2.99 -0.45 0)
			(layer "B.SilkS")
			(effects
				(font
					(size 0.7 0.7)
					(thickness 0.15)
				)
				(justify left bottom mirror)
			)
		)
		(property "Value" "C_1u_25V_0402"
			(at -1.022927 -2.155213 0)
			(layer "B.Fab")
			(hide yes)
			(effects
				(font
					(size 0.7 0.7)
					(thickness 0.15)
				)
				(justify left bottom mirror)
			)
		)
		(property "Datasheet" "https://www.murata.com/products/productdetail?partno=GRM155R61E105KE11%23"
			(at 0 0 0)
			(layer "B.Fab")
			(hide yes)
			(effects
				(font
					(size 1.27 1.27)
					(thickness 0.15)
				)
				(justify mirror)
			)
		)
		(property "Description" "SMD Multilayer Ceramic Capacitor, 1 µF, 25 V, 0402 [1005 Metric], ± 10%, X5R, GRM Series"
			(at 0 0 0)
			(layer "B.Fab")
			(hide yes)
			(effects
				(font
					(size 1.27 1.27)
					(thickness 0.15)
				)
				(justify mirror)
			)
		)
		(property "MPN" "GRM155R61E105KE11J"
			(at 0 0 180)
			(unlocked yes)
			(layer "B.Fab")
			(hide yes)
			(effects
				(font
					(size 1 1)
					(thickness 0.15)
				)
				(justify mirror)
			)
		)
		(property "Manufacturer" "Murata"
			(at 0 0 180)
			(unlocked yes)
			(layer "B.Fab")
			(hide yes)
			(effects
				(font
					(size 1 1)
					(thickness 0.15)
				)
				(justify mirror)
			)
		)
		(property "License" "Apache-2.0"
			(at 0 0 180)
			(unlocked yes)
			(layer "B.Fab")
			(hide yes)
			(effects
				(font
					(size 1 1)
					(thickness 0.15)
				)
				(justify mirror)
			)
		)
		(property "Author" "Antmicro"
			(at 0 0 180)
			(unlocked yes)
			(layer "B.Fab")
			(hide yes)
			(effects
				(font
					(size 1 1)
					(thickness 0.15)
				)
				(justify mirror)
			)
		)
		(property "Val" "1u"
			(at 0 0 180)
			(unlocked yes)
			(layer "B.Fab")
			(hide yes)
			(effects
				(font
					(size 1 1)
					(thickness 0.15)
				)
				(justify mirror)
			)
		)
		(property "Voltage" "25V"
			(at 0 0 180)
			(unlocked yes)
			(layer "B.Fab")
			(hide yes)
			(effects
				(font
					(size 1 1)
					(thickness 0.15)
				)
				(justify mirror)
			)
		)
		(property "Dielectric" "X5R"
			(at 0 0 180)
			(unlocked yes)
			(layer "B.Fab")
			(hide yes)
			(effects
				(font
					(size 1 1)
					(thickness 0.15)
				)
				(justify mirror)
			)
		)
		(sheetname "/2xRJ45/")
		(sheetfile "2xrj45.kicad_sch")
		(attr smd)
		(fp_rect
			(start -0.925 0.47)
			(end 0.925 -0.47)
			(stroke
				(width 0.05)
				(type default)
			)
			(fill no)
			(layer "B.CrtYd")
		)
		(fp_line
			(start 0.504 0.25)
			(end 0.504 -0.248)
			(stroke
				(width 0.15)
				(type solid)
			)
			(layer "B.Fab")
		)
		(fp_line
			(start 0.504 -0.248)
			(end -0.494 -0.248)
			(stroke
				(width 0.15)
				(type solid)
			)
			(layer "B.Fab")
		)
		(fp_line
			(start -0.494 0.25)
			(end 0.504 0.25)
			(stroke
				(width 0.15)
				(type solid)
			)
			(layer "B.Fab")
		)
		(fp_line
			(start -0.494 -0.248)
			(end -0.494 0.25)
			(stroke
				(width 0.15)
				(type solid)
			)
			(layer "B.Fab")
		)
		(pad "1" smd roundrect
			(at -0.48 0 180)
			(size 0.59 0.64)
			(layers "B.Cu" "B.Mask" "B.Paste")
			(roundrect_rratio 0.25)
			(net 28 "GND")
			(pintype "passive")
		)
		(pad "2" smd roundrect
			(at 0.48 0 180)
			(size 0.59 0.64)
			(layers "B.Cu" "B.Mask" "B.Paste")
			(roundrect_rratio 0.25)
			(net 300 "/2xRJ45/P1_CT")
			(pintype "passive")
		)
	)
	(footprint "antmicro-footprints:R_0402_1005Metric"
		(layer "B.Cu")
		(at 100.62 90.644 90)
		(descr "Resistor SMD 0402")
		(tags "resistor SMD 0402")
		(property "Reference" "R126"
			(at -0.806 0.43 90)
			(layer "B.SilkS")
			(effects
				(font
					(size 0.7 0.7)
					(thickness 0.15)
				)
				(justify left bottom mirror)
			)
		)
		(property "Value" "R_49R9_0402"
			(at -1.011843 -1.772047 90)
			(layer "B.Fab")
			(hide yes)
			(effects
				(font
					(size 0.7 0.7)
					(thickness 0.15)
				)
				(justify right top mirror)
			)
		)
		(property "Datasheet" "https://www.bourns.com/docs/product-datasheets/cr.pdf"
			(at 0 0 90)
			(layer "B.Fab")
			(hide yes)
			(effects
				(font
					(size 1.27 1.27)
					(thickness 0.15)
				)
				(justify mirror)
			)
		)
		(property "Description" "SMD Chip Resistor, 49.9 ohm, ± 1%, 62.5 mW, 0402 [1005 Metric], Thick Film, General Purpose"
			(at 0 0 90)
			(layer "B.Fab")
			(hide yes)
			(effects
				(font
					(size 1.27 1.27)
					(thickness 0.15)
				)
				(justify mirror)
			)
		)
		(property "MPN" "CR0402-FX-49R9GLF"
			(at 0 0 270)
			(unlocked yes)
			(layer "B.Fab")
			(hide yes)
			(effects
				(font
					(size 1 1)
					(thickness 0.15)
				)
				(justify mirror)
			)
		)
		(property "Manufacturer" "Bourns"
			(at 0 0 270)
			(unlocked yes)
			(layer "B.Fab")
			(hide yes)
			(effects
				(font
					(size 1 1)
					(thickness 0.15)
				)
				(justify mirror)
			)
		)
		(property "License" "Apache-2.0"
			(at 0 0 270)
			(unlocked yes)
			(layer "B.Fab")
			(hide yes)
			(effects
				(font
					(size 1 1)
					(thickness 0.15)
				)
				(justify mirror)
			)
		)
		(property "Author" "Antmicro"
			(at 0 0 270)
			(unlocked yes)
			(layer "B.Fab")
			(hide yes)
			(effects
				(font
					(size 1 1)
					(thickness 0.15)
				)
				(justify mirror)
			)
		)
		(property "Val" "49R9"
			(at 0 0 270)
			(unlocked yes)
			(layer "B.Fab")
			(hide yes)
			(effects
				(font
					(size 1 1)
					(thickness 0.15)
				)
				(justify mirror)
			)
		)
		(property "Tolerance" "1%"
			(at 0 0 270)
			(unlocked yes)
			(layer "B.Fab")
			(hide yes)
			(effects
				(font
					(size 1 1)
					(thickness 0.15)
				)
				(justify mirror)
			)
		)
		(sheetname "/X710-AT2 PCIe/")
		(sheetfile "x710-at2-pcie.kicad_sch")
		(attr smd exclude_from_pos_files exclude_from_bom dnp)
		(fp_rect
			(start -0.925 0.47)
			(end 0.925 -0.47)
			(stroke
				(width 0.05)
				(type default)
			)
			(fill no)
			(layer "B.CrtYd")
		)
		(fp_rect
			(start -0.5 0.25)
			(end 0.5 -0.25)
			(stroke
				(width 0.15)
				(type solid)
			)
			(fill no)
			(layer "B.Fab")
		)
		(pad "1" smd roundrect
			(at -0.48 0 90)
			(size 0.59 0.64)
			(layers "B.Cu" "B.Mask" "B.Paste")
			(roundrect_rratio 0.25)
			(net 28 "GND")
			(pintype "passive")
		)
		(pad "2" smd roundrect
			(at 0.48 0 90)
			(size 0.59 0.64)
			(layers "B.Cu" "B.Mask" "B.Paste")
			(roundrect_rratio 0.25)
			(net 405 "/X710-AT2 PCIe/GEN_F_CLK+")
			(pintype "passive")
		)
	)
	(footprint "antmicro-footprints:C_0402_1005Metric"
		(layer "B.Cu")
		(at 89.225 98.294031 90)
		(descr "Capacitor SMD 0402")
		(tags "capacitor SMD 0402")
		(property "Reference" "C110"
			(at 10.69 -0.467857 90)
			(layer "B.SilkS")
			(effects
				(font
					(size 0.7 0.7)
					(thickness 0.15)
				)
				(justify right top mirror)
			)
		)
		(property "Value" "C_1u_25V_0402"
			(at -1.022927 -2.155213 90)
			(layer "B.Fab")
			(hide yes)
			(effects
				(font
					(size 0.7 0.7)
					(thickness 0.15)
				)
				(justify right top mirror)
			)
		)
		(property "Datasheet" "https://www.murata.com/products/productdetail?partno=GRM155R61E105KE11%23"
			(at 0 0 90)
			(layer "B.Fab")
			(hide yes)
			(effects
				(font
					(size 1.27 1.27)
					(thickness 0.15)
				)
				(justify mirror)
			)
		)
		(property "Description" "SMD Multilayer Ceramic Capacitor, 1 µF, 25 V, 0402 [1005 Metric], ± 10%, X5R, GRM Series"
			(at 0 0 90)
			(layer "B.Fab")
			(hide yes)
			(effects
				(font
					(size 1.27 1.27)
					(thickness 0.15)
				)
				(justify mirror)
			)
		)
		(property "MPN" "GRM155R61E105KE11J"
			(at 0 0 90)
			(unlocked yes)
			(layer "B.Fab")
			(hide yes)
			(effects
				(font
					(size 1 1)
					(thickness 0.15)
				)
				(justify mirror)
			)
		)
		(property "Manufacturer" "Murata"
			(at 0 0 90)
			(unlocked yes)
			(layer "B.Fab")
			(hide yes)
			(effects
				(font
					(size 1 1)
					(thickness 0.15)
				)
				(justify mirror)
			)
		)
		(property "License" "Apache-2.0"
			(at 0 0 90)
			(unlocked yes)
			(layer "B.Fab")
			(hide yes)
			(effects
				(font
					(size 1 1)
					(thickness 0.15)
				)
				(justify mirror)
			)
		)
		(property "Author" "Antmicro"
			(at 0 0 90)
			(unlocked yes)
			(layer "B.Fab")
			(hide yes)
			(effects
				(font
					(size 1 1)
					(thickness 0.15)
				)
				(justify mirror)
			)
		)
		(property "Val" "1u"
			(at 0 0 90)
			(unlocked yes)
			(layer "B.Fab")
			(hide yes)
			(effects
				(font
					(size 1 1)
					(thickness 0.15)
				)
				(justify mirror)
			)
		)
		(property "Voltage" "25V"
			(at 0 0 90)
			(unlocked yes)
			(layer "B.Fab")
			(hide yes)
			(effects
				(font
					(size 1 1)
					(thickness 0.15)
				)
				(justify mirror)
			)
		)
		(property "Dielectric" "X5R"
			(at 0 0 90)
			(unlocked yes)
			(layer "B.Fab")
			(hide yes)
			(effects
				(font
					(size 1 1)
					(thickness 0.15)
				)
				(justify mirror)
			)
		)
		(sheetname "/X710-AT2 power/")
		(sheetfile "x710-at2-power.kicad_sch")
		(attr smd)
		(fp_rect
			(start -0.925 0.47)
			(end 0.925 -0.47)
			(stroke
				(width 0.05)
				(type default)
			)
			(fill no)
			(layer "B.CrtYd")
		)
		(fp_line
			(start 0.504 -0.248)
			(end -0.494 -0.248)
			(stroke
				(width 0.15)
				(type solid)
			)
			(layer "B.Fab")
		)
		(fp_line
			(start -0.494 -0.248)
			(end -0.494 0.25)
			(stroke
				(width 0.15)
				(type solid)
			)
			(layer "B.Fab")
		)
		(fp_line
			(start 0.504 0.25)
			(end 0.504 -0.248)
			(stroke
				(width 0.15)
				(type solid)
			)
			(layer "B.Fab")
		)
		(fp_line
			(start -0.494 0.25)
			(end 0.504 0.25)
			(stroke
				(width 0.15)
				(type solid)
			)
			(layer "B.Fab")
		)
		(pad "1" smd roundrect
			(at -0.48 0 90)
			(size 0.59 0.64)
			(layers "B.Cu" "B.Mask" "B.Paste")
			(roundrect_rratio 0.25)
			(net 28 "GND")
			(pintype "passive")
		)
		(pad "2" smd roundrect
			(at 0.48 0 90)
			(size 0.59 0.64)
			(layers "B.Cu" "B.Mask" "B.Paste")
			(roundrect_rratio 0.25)
			(net 9 "VCCD")
			(pintype "passive")
		)
	)
)
